FILE_TYPE = CONNECTIVITY;
{Allegro Design Entry HDL 17.2-2016 S081 (4005846) 1/11/2022}
"PAGE_NUMBER" = 224;
0"NC";
1"P3V3_AUX\g";
2"PVNN_TERM_CPU0\g";
3"PVNN_TERM_CPU1\g";
4"P3V3_AUX\g";
5"P3V3_AUX\g";
6"P3V3_AUX\g";
7"P3V3_AUX\g";
8"P3V3_AUX\g";
9"P3V3_AUX\g";
10"PVNN_TERM_CPU0\g";
11"PVNN_TERM_CPU1\g";
12"P3V3_AUX\g";
13"P3V3_AUX\g";
14"GND\g";
15"GND\g";
16"GND\g";
17"GND\g";
18"GND\g";
19"GND\g";
20"GND\g";
21"GND\g";
22"GND\g";
23"SMB_S3M_CPU1_3V3AUX_SCL"CDS_PHYS_NET_NAME"SMB_S3M_CPU1_3V3AUX_SCL";
24"PCA9545_S3M_INT_N";
25"RST_SMB_SWITCH_N"CDS_PHYS_NET_NAME"RST_SMB_SWITCH_N";
26"PCA9543_S3M_INT3_N";
27"PCA9543_S3M_ADDR1";
28"PCA9543_S3M_ADDR0";
29"SMB_S3M_CPU1_PIROM_3V3AUX_SCL_R";
30"PCA9543_S3M_INT2_N";
31"RST_SMB_S3M_N"CDS_PHYS_NET_NAME"RST_SMB_PCIE1_N";
32"PCA9543_S3M_ADDR0";
33"PCA9543_S3M_ADDR1";
34"SMB_S3M_CPU_3V3AUX_SDA";
35"PCA9543_S3M_INT0_N";
36"SMB_S3M_CPU0_3V3AUX_SDA_R";
37"SMB_S3M_CPU1_R_SCL"CDS_PHYS_NET_NAME"SMB_S3M_CPU1_R_SCL";
38"SMB_S3M_CPU1_SDA"CDS_PHYS_NET_NAME"SMB_S3M_CPU1_SDA";
39"SMB_S3M_CPU1_R_SDA"CDS_PHYS_NET_NAME"SMB_S3M_CPU1_R_SDA";
40"SMB_S3M_CPU0_SDA"CDS_PHYS_NET_NAME"SMB_S3M_CPU0_SDA";
41"SMB_S3M_CPU0_R_SDA"CDS_PHYS_NET_NAME"SMB_S3M_CPU0_R_SDA";
42"SMB_S3M_CPU0_R_SCL"CDS_PHYS_NET_NAME"SMB_S3M_CPU0_R_SCL";
43"SMB_S3M_CPU_3V3AUX_SCL";
44"TP_SMB_S3M_CPU0_EN"CDS_PHYS_NET_NAME"TP_SMB_S3M_CPU0_EN";
45"TP_SMB_S3M_CPU1_EN"CDS_PHYS_NET_NAME"TP_SMB_S3M_CPU1_EN";
46"SMB_S3M_CPU1_3V3AUX_SCL";
47"SMB_S3M_CPU0_3V3AUX_SDA";
48"SMB_S3M_CPU1_PIROM_3V3AUX_SDA_R";
49"SMB_S3M_CPU0_PIROM_3V3AUX_SCL_R";
50"SMB_S3M_CPU0_3V3AUX_SCL";
51"SMB_S3M_CPU1_3V3AUX_SDA";
52"SMB_S3M_CPU0_3V3AUX_SDA"CDS_PHYS_NET_NAME"SMB_S3M_CPU0_3V3AUX_SDA";
53"SMB_S3M_CPU0_3V3AUX_SCL"CDS_PHYS_NET_NAME"SMB_S3M_CPU0_3V3AUX_SCL";
54"SMB_S3M_CPU1_3V3AUX_SDA"CDS_PHYS_NET_NAME"SMB_S3M_CPU1_3V3AUX_SDA";
55"SMB_S3M_CPU0_3V3AUX_SCL_R";
56"SMB_S3M_CPU0_PIROM_3V3AUX_SCL";
57"SMB_S3M_CPU0_PIROM_3V3AUX_SDA";
58"SMB_S3M_CPU1_PIROM_3V3AUX_SCL";
59"SMB_S3M_CPU1_PIROM_3V3AUX_SDA";
60"SMB_S3M_CPU1_PIROM_3V3AUX_SDA";
61"SMB_S3M_CPU1_PIROM_3V3AUX_SCL";
62"SMB_S3M_CPU0_PIROM_3V3AUX_SDA_R";
63"SMB_S3M_CPU1_3V3AUX_SCL_R";
64"SMB_S3M_CPU1_3V3AUX_SDA_R";
65"PCA9543_S3M_INT1_N";
66"SMB_S3M_CPU0_PIROM_3V3AUX_SDA";
67"SMB_S3M_CPU0_PIROM_3V3AUX_SCL";
68"SMB_S3M_CPU0_SCL"CDS_PHYS_NET_NAME"SMB_S3M_CPU0_SCL";
69"SMB_S3M_CPU1_SCL"CDS_PHYS_NET_NAME"SMB_S3M_CPU1_SCL";
%"Q_RES"
"2","(-2800,9150)","0","pure_quanta","I101";
;
PART_NUMBER"CS31002FB08"
PACK_TYPE"0402LF"
MATERIAL"CHIP"
WATTAGE"1/16W"
TOLERANCE"1%"
VALUE"10K"
$LOCATION"R2312"
CDS_LIB"pure_quanta"
CDS_LOCATION"R2312"
$SEC"1"
CDS_SEC"1";
"A"
$PN"1"6;
"B"
$PN"2"24;
%"UNIVERSAL_POWER"
"1","(-2800,9500)","0","logical_power","I102";
;
HDL_POWER"P3V3_AUX"
CDS_LIB"logical_power";
"A"6;
%"Q_RES"
"2","(3275,9200)","0","pure_quanta","I103";
;
PART_NUMBER"CS31002FB08"
VALUE"10K"
TOLERANCE"1%"
PACK_TYPE"0402LF"
WATTAGE"1/16W"
MATERIAL"CHIP"
$LOCATION"R2315"
CDS_LIB"pure_quanta"
CDS_LOCATION"R2315"
$SEC"1"
CDS_SEC"1";
"A"
$PN"1"8;
"B"
$PN"2"35;
%"UNIVERSAL_POWER"
"1","(4200,9550)","0","logical_power","I104";
;
HDL_POWER"P3V3_AUX"
CDS_LIB"logical_power";
"A"8;
%"PCA9545APW"
"1","(-250,8400)","0","pure_quanta","I106";
;
PART_NUMBER"AL009545K17"
MATERIAL"IC"
VALUE"PCA9545APW"
PART_TYPE"SMLF"
LOCATION"U143"
CDS_LIB"pure_quanta"
NEEDS_NO_SIZE"TRUE"
CDS_LMAN_SYM_OUTLINE"-300,600,300,-600"
SEC_TYPE""
SEC"1";
"INT3# \B"
$PN"14"26;
"SC3"
$PN"16"29;
"SD3"
$PN"15"48;
"INT2# \B"
$PN"11"30;
"SC2"
$PN"13"49;
"SD2"
$PN"12"62;
"INT1# \B"
$PN"7"65;
"SC1"
$PN"9"63;
"SD1"
$PN"8"64;
"INT0# \B"
$PN"4"35;
"SC0"
$PN"6"55;
"SD0"
$PN"5"36;
"VDD"
$PN"20"7;
"VSS"
$PN"10"22;
"SDA"
$PN"19"34;
"SCL"
$PN"18"43;
"INT# \B"
$PN"17"24;
"RESET# \B"
$PN"3"31;
"A1"
$PN"2"27;
"A0"
$PN"1"28;
%"Q_RES"
"2","(3600,9200)","0","pure_quanta","I109";
;
PART_NUMBER"CS31002FB08"
TOLERANCE"1%"
VALUE"10K"
PACK_TYPE"0402LF"
MATERIAL"CHIP"
WATTAGE"1/16W"
$LOCATION"R3127"
CDS_LIB"pure_quanta"
CDS_LOCATION"R3127"
$SEC"1"
CDS_SEC"1";
"A"
$PN"1"8;
"B"
$PN"2"65;
%"Q_RES"
"2","(3900,9200)","0","pure_quanta","I110";
;
PART_NUMBER"CS31002FB08"
PACK_TYPE"0402LF"
MATERIAL"CHIP"
WATTAGE"1/16W"
VALUE"10K"
TOLERANCE"1%"
$LOCATION"R3130"
CDS_LIB"pure_quanta"
CDS_LOCATION"R3130"
$SEC"1"
CDS_SEC"1";
"A"
$PN"1"8;
"B"
$PN"2"30;
%"Q_RES"
"2","(4200,9200)","0","pure_quanta","I111";
;
PART_NUMBER"CS31002FB08"
PACK_TYPE"0402LF"
MATERIAL"CHIP"
WATTAGE"1/16W"
TOLERANCE"1%"
VALUE"10K"
$LOCATION"R3131"
CDS_LIB"pure_quanta"
CDS_LOCATION"R3131"
$SEC"1"
CDS_SEC"1";
"A"
$PN"1"8;
"B"
$PN"2"26;
%"Q_RES"
"1","(1475,8250)","0","pure_quanta","I114";
;
PART_NUMBER"CS00002JB13"
MATERIAL"CHIP"
VALUE"0"
TOLERANCE"5%"
$LOCATION"R3124"
PACK_TYPE"0402LF"
WATTAGE"1/16W"
CDS_LIB"pure_quanta"
CDS_LOCATION"R3124"
$SEC"1"
CDS_SEC"1";
"B"
$PN"2"57;
"A"
$PN"1"62;
%"Q_RES"
"1","(1475,8300)","0","pure_quanta","I115";
;
PART_NUMBER"CS00002JB13"
MATERIAL"CHIP"
TOLERANCE"5%"
VALUE"0"
$LOCATION"R3123"
CDS_LIB"pure_quanta"
WATTAGE"1/16W"
PACK_TYPE"0402LF"
CDS_LOCATION"R3123"
$SEC"1"
CDS_SEC"1";
"B"
$PN"2"56;
"A"
$PN"1"49;
%"Q_RES"
"1","(1475,8000)","0","pure_quanta","I116";
;
PART_NUMBER"CS00002JB13"
VALUE"0"
MATERIAL"CHIP"
TOLERANCE"5%"
$LOCATION"R3125"
PACK_TYPE"0402LF"
WATTAGE"1/16W"
CDS_LIB"pure_quanta"
CDS_LOCATION"R3125"
$SEC"1"
CDS_SEC"1";
"B"
$PN"2"61;
"A"
$PN"1"29;
%"Q_RES"
"1","(1475,7950)","0","pure_quanta","I117";
;
PART_NUMBER"CS00002JB13"
MATERIAL"CHIP"
TOLERANCE"5%"
VALUE"0"
$LOCATION"R3126"
CDS_LIB"pure_quanta"
WATTAGE"1/16W"
PACK_TYPE"0402LF"
CDS_LOCATION"R3126"
$SEC"1"
CDS_SEC"1";
"B"
$PN"2"60;
"A"
$PN"1"48;
%"Q_RES"
"2","(1750,4800)","0","pure_quanta","I13";
;
PART_NUMBER"CS00002JB13"
VALUE"0"
MATERIAL"EMPTY"
WATTAGE"1/16W"
TOLERANCE"5%"
PACK_TYPE"0402LF"
$LOCATION"R448"
CDS_LIB"pure_quanta"
CDS_LOCATION"R448"
$SEC"1"
CDS_SEC"1";
"A"
$PN"1"53;
"B"
$PN"2"23;
%"Q_RES"
"1","(3650,6450)","0","pure_quanta","I130";
;
PART_NUMBER"CS22002FB07"
TOLERANCE"1%"
VALUE"2K"
MATERIAL"CHIP"
$LOCATION"R3225"
WATTAGE"1/16W"
PACK_TYPE"0402LF"
CDS_LIB"pure_quanta"
CDS_LOCATION"R3225"
$SEC"1"
CDS_SEC"1";
"B"
$PN"2"9;
"A"
$PN"1"59;
%"Q_RES"
"1","(3650,6500)","0","pure_quanta","I131";
;
PART_NUMBER"CS22002FB07"
WATTAGE"1/16W"
VALUE"2K"
MATERIAL"CHIP"
TOLERANCE"1%"
PACK_TYPE"0402LF"
$LOCATION"R3224"
CDS_LIB"pure_quanta"
CDS_LOCATION"R3224"
$SEC"1"
CDS_SEC"1";
"B"
$PN"2"9;
"A"
$PN"1"58;
%"Q_RES"
"1","(3650,6800)","0","pure_quanta","I132";
;
PART_NUMBER"CS22002FB07"
PACK_TYPE"0402LF"
MATERIAL"CHIP"
VALUE"2K"
WATTAGE"1/16W"
TOLERANCE"1%"
$LOCATION"R3222"
CDS_LIB"pure_quanta"
CDS_LOCATION"R3222"
$SEC"1"
CDS_SEC"1";
"B"
$PN"2"9;
"A"
$PN"1"67;
%"Q_RES"
"1","(3650,6750)","0","pure_quanta","I133";
;
PART_NUMBER"CS22002FB07"
VALUE"2K"
TOLERANCE"1%"
MATERIAL"CHIP"
$LOCATION"R3223"
PACK_TYPE"0402LF"
WATTAGE"1/16W"
CDS_LIB"pure_quanta"
CDS_LOCATION"R3223"
$SEC"1"
CDS_SEC"1";
"B"
$PN"2"9;
"A"
$PN"1"66;
%"UNIVERSAL_POWER"
"1","(4200,7075)","0","logical_power","I138";
;
HDL_POWER"P3V3_AUX"
CDS_LIB"logical_power";
"A"9;
%"Q_RES"
"2","(1350,4400)","0","pure_quanta","I14";
;
PART_NUMBER"CS15602FB03"
WATTAGE"1/16W"
TOLERANCE"1%"
VALUE"560"
PACK_TYPE"0402LF"
MATERIAL"CHIP"
$LOCATION"R980"
CDS_LIB"pure_quanta"
CDS_LOCATION"R980"
$SEC"1"
CDS_SEC"1";
"A"
$PN"1"1;
"B"
$PN"2"54;
%"Q_RES"
"1","(-3175,5650)","0","pure_quanta","I142";
;
PART_NUMBER"CS03322FB03"
VALUE"33.2"
TOLERANCE"1%"
MATERIAL"CHIP"
LOCATION"R994"
WATTAGE"1/16W"
PACK_TYPE"0402LF"
CDS_LIB"pure_quanta"
$SEC"1"
CDS_SEC"1";
"B"
$PN"2"41;
"A"
$PN"1"40;
%"Q_RES"
"1","(-3175,3850)","0","pure_quanta","I143";
;
PART_NUMBER"CS03322FB03"
MATERIAL"CHIP"
TOLERANCE"1%"
VALUE"33.2"
LOCATION"R996"
PACK_TYPE"0402LF"
WATTAGE"1/16W"
CDS_LIB"pure_quanta"
$SEC"1"
CDS_SEC"1";
"B"
$PN"2"39;
"A"
$PN"1"38;
%"UNIVERSAL_POWER"
"1","(1150,4750)","0","logical_power","I15";
;
HDL_POWER"P3V3_AUX"
CDS_LIB"logical_power";
"A"1;
%"Q_RES"
"2","(1150,4400)","0","pure_quanta","I16";
;
PART_NUMBER"CS15602FB03"
TOLERANCE"1%"
PACK_TYPE"0402LF"
VALUE"560"
MATERIAL"CHIP"
WATTAGE"1/16W"
$LOCATION"R978"
CDS_LIB"pure_quanta"
CDS_LOCATION"R978"
$SEC"1"
CDS_SEC"1";
"A"
$PN"1"1;
"B"
$PN"2"23;
%"UNIVERSAL_POWER"
"1","(-475,6550)","0","logical_power","I21";
;
HDL_POWER"P3V3_AUX"
CDS_LIB"logical_power";
"A"13;
%"Q_CAP"
"1","(-475,6225)","0","pure_quanta","I22";
;
PART_NUMBER"CH4104K1B00"
PACK_TYPE"0402"
VALUE"0.1UF"
MATERIAL"X7R"
VOLTAGE"25V"
TOLERANCE"10%"
$LOCATION"C569"
CDS_LIB"pure_quanta"
$LOCATION"C569"
CDS_LOCATION"C569"
$SEC"1"
CDS_SEC"1";
"B"
$PN"2"19;
"A"
$PN"1"13;
%"UNIVERSAL_GND"
"1","(-475,6000)","0","logical_power","I23";
;
CDS_LIB"logical_power"
HDL_POWER"GND";
"A"19;
%"UNIVERSAL_POWER"
"1","(-1825,6550)","0","logical_power","I24";
;
HDL_POWER"PVNN_TERM_CPU0"
CDS_LIB"logical_power";
"A"10;
%"Q_CAP"
"1","(-1825,6225)","2","pure_quanta","I25";
;
PART_NUMBER"CH4104K1B00"
VALUE"0.1UF"
PACK_TYPE"0402"
MATERIAL"X7R"
VOLTAGE"25V"
TOLERANCE"10%"
$LOCATION"C567"
CDS_LIB"pure_quanta"
$LOCATION"C567"
CDS_LOCATION"C567"
$SEC"1"
CDS_SEC"1";
"B"
$PN"2"17;
"A"
$PN"1"10;
%"UNIVERSAL_GND"
"1","(-1825,6000)","0","logical_power","I26";
;
HDL_POWER"GND"
CDS_LIB"logical_power";
"A"17;
%"PCA9517AD"
"1","(-1125,5700)","0","pure_quanta","I28";
;
PART_NUMBER"AL009517000"
VALUE"PCA9517AD"
PART_TYPE"SMLF"
MATERIAL"IC"
$LOCATION"U30"
CDS_LIB"pure_quanta"
NEEDS_NO_SIZE"TRUE"
CDS_LOCATION"U30"
$SEC"1"
CDS_SEC"1";
"GND"
$PN"4"16;
"SCLB"
$PN"7"53;
"SDAB"
$PN"6"52;
"SDAA"
$PN"3"41;
"SCLA"
$PN"2"42;
"VCCB"
$PN"8"13;
"VCCA"
$PN"1"10;
"ENABLE"
$PN"5"44;
%"UNIVERSAL_GND"
"1","(-1675,5350)","0","logical_power","I29";
;
HDL_POWER"GND"
CDS_LIB"logical_power";
"A"16;
%"Q_RES"
"2","(2000,4800)","0","pure_quanta","I3";
;
PART_NUMBER"CS00002JB13"
TOLERANCE"5%"
MATERIAL"EMPTY"
VALUE"0"
WATTAGE"1/16W"
PACK_TYPE"0402LF"
$LOCATION"R1648"
CDS_LIB"pure_quanta"
CDS_LOCATION"R1648"
$SEC"1"
CDS_SEC"1";
"A"
$PN"1"52;
"B"
$PN"2"54;
%"UNIVERSAL_POWER"
"1","(-475,4750)","0","logical_power","I31";
;
HDL_POWER"P3V3_AUX"
CDS_LIB"logical_power";
"A"4;
%"UNIVERSAL_GND"
"1","(-475,4200)","0","logical_power","I32";
;
CDS_LIB"logical_power"
HDL_POWER"GND";
"A"18;
%"Q_CAP"
"1","(-475,4425)","0","pure_quanta","I33";
;
PART_NUMBER"CH4104K1B00"
VOLTAGE"25V"
TOLERANCE"10%"
VALUE"0.1UF"
PACK_TYPE"0402"
MATERIAL"X7R"
$LOCATION"C570"
CDS_LIB"pure_quanta"
$LOCATION"C570"
CDS_LOCATION"C570"
$SEC"1"
CDS_SEC"1";
"B"
$PN"2"18;
"A"
$PN"1"4;
%"UNIVERSAL_POWER"
"1","(-1825,4750)","0","logical_power","I34";
;
HDL_POWER"PVNN_TERM_CPU1"
CDS_LIB"logical_power";
"A"3;
%"Q_CAP"
"1","(-1825,4425)","2","pure_quanta","I35";
;
PART_NUMBER"CH4104K1B00"
VALUE"0.1UF"
VOLTAGE"25V"
TOLERANCE"10%"
MATERIAL"X7R"
PACK_TYPE"0402"
$LOCATION"C568"
CDS_LIB"pure_quanta"
$LOCATION"C568"
CDS_LOCATION"C568"
$SEC"1"
CDS_SEC"1";
"B"
$PN"2"15;
"A"
$PN"1"3;
%"UNIVERSAL_GND"
"1","(-1825,4200)","0","logical_power","I36";
;
CDS_LIB"logical_power"
HDL_POWER"GND";
"A"15;
%"PCA9517AD"
"1","(-1125,3900)","0","pure_quanta","I37";
;
PART_NUMBER"AL009517000"
MATERIAL"IC"
PART_TYPE"SMLF"
VALUE"PCA9517AD"
$LOCATION"U31"
CDS_LIB"pure_quanta"
NEEDS_NO_SIZE"TRUE"
CDS_LOCATION"U31"
$SEC"1"
CDS_SEC"1";
"GND"
$PN"4"14;
"SCLB"
$PN"7"23;
"SDAB"
$PN"6"54;
"SDAA"
$PN"3"39;
"SCLA"
$PN"2"37;
"VCCB"
$PN"8"4;
"VCCA"
$PN"1"3;
"ENABLE"
$PN"5"45;
%"UNIVERSAL_GND"
"1","(-1675,3550)","0","logical_power","I38";
;
CDS_LIB"logical_power"
HDL_POWER"GND";
"A"14;
%"UNIVERSAL_POWER"
"1","(-2725,6550)","0","logical_power","I41";
;
HDL_POWER"PVNN_TERM_CPU0"
CDS_LIB"logical_power";
"A"2;
%"Q_RES"
"2","(-2500,6200)","2","pure_quanta","I42";
;
PART_NUMBER"CS12402FB01"
WATTAGE"1/16W"
PACK_TYPE"0402LF"
MATERIAL"CHIP"
VALUE"240"
TOLERANCE"1%"
$LOCATION"R971"
CDS_LIB"pure_quanta"
$LOCATION"R971"
CDS_LOCATION"R971"
$SEC"1"
CDS_SEC"1";
"A"
$PN"1"2;
"B"
$PN"2"41;
%"Q_RES"
"2","(-2725,6200)","2","pure_quanta","I43";
;
PART_NUMBER"CS12402FB01"
PACK_TYPE"0402LF"
MATERIAL"CHIP"
WATTAGE"1/16W"
TOLERANCE"1%"
VALUE"240"
$LOCATION"R969"
CDS_LIB"pure_quanta"
$LOCATION"R969"
CDS_LOCATION"R969"
$SEC"1"
CDS_SEC"1";
"A"
$PN"1"2;
"B"
$PN"2"42;
%"Q_RES"
"1","(-3175,5750)","0","pure_quanta","I44";
;
PART_NUMBER"CS03322FB03"
MATERIAL"CHIP"
TOLERANCE"1%"
VALUE"33.2"
$LOCATION"R993"
PACK_TYPE"0402LF"
WATTAGE"1/16W"
CDS_LIB"pure_quanta"
CDS_LOCATION"R993"
$SEC"1"
CDS_SEC"1";
"B"
$PN"2"42;
"A"
$PN"1"68;
%"UNIVERSAL_POWER"
"1","(-2725,4750)","0","logical_power","I48";
;
HDL_POWER"PVNN_TERM_CPU1"
CDS_LIB"logical_power";
"A"11;
%"Q_RES"
"2","(-2500,4400)","2","pure_quanta","I49";
;
PART_NUMBER"CS12402FB01"
MATERIAL"CHIP"
VALUE"240"
PACK_TYPE"0402LF"
TOLERANCE"1%"
WATTAGE"1/16W"
$LOCATION"R972"
CDS_LIB"pure_quanta"
$LOCATION"R972"
CDS_LOCATION"R972"
$SEC"1"
CDS_SEC"1";
"A"
$PN"1"11;
"B"
$PN"2"39;
%"Q_RES"
"2","(-2725,4400)","2","pure_quanta","I50";
;
PART_NUMBER"CS12402FB01"
WATTAGE"1/16W"
TOLERANCE"1%"
PACK_TYPE"0402LF"
MATERIAL"CHIP"
VALUE"240"
$LOCATION"R970"
CDS_LIB"pure_quanta"
$LOCATION"R970"
CDS_LOCATION"R970"
$SEC"1"
CDS_SEC"1";
"A"
$PN"1"11;
"B"
$PN"2"37;
%"Q_RES"
"1","(-3175,3950)","0","pure_quanta","I51";
;
PART_NUMBER"CS03322FB03"
VALUE"33.2"
MATERIAL"CHIP"
TOLERANCE"1%"
$LOCATION"R995"
PACK_TYPE"0402LF"
WATTAGE"1/16W"
CDS_LIB"pure_quanta"
CDS_LOCATION"R995"
$SEC"1"
CDS_SEC"1";
"B"
$PN"2"37;
"A"
$PN"1"69;
%"Q_RES"
"2","(1350,6200)","0","pure_quanta","I6";
;
PART_NUMBER"CS15602FB03"
PACK_TYPE"0402LF"
MATERIAL"CHIP"
TOLERANCE"1%"
VALUE"560"
WATTAGE"1/16W"
$LOCATION"R979"
CDS_LIB"pure_quanta"
CDS_LOCATION"R979"
$SEC"1"
CDS_SEC"1";
"A"
$PN"1"12;
"B"
$PN"2"52;
%"Q_RES"
"1","(1475,8850)","0","pure_quanta","I62";
;
PART_NUMBER"CS00002JB13"
VALUE"0"
TOLERANCE"5%"
MATERIAL"CHIP"
$LOCATION"R2208"
PACK_TYPE"0402LF"
WATTAGE"1/16W"
CDS_LIB"pure_quanta"
CDS_LOCATION"R2208"
$SEC"1"
CDS_SEC"1";
"B"
$PN"2"47;
"A"
$PN"1"36;
%"Q_RES"
"1","(1475,8900)","0","pure_quanta","I63";
;
PART_NUMBER"CS00002JB13"
VALUE"0"
TOLERANCE"5%"
MATERIAL"CHIP"
$LOCATION"R2209"
CDS_LIB"pure_quanta"
WATTAGE"1/16W"
PACK_TYPE"0402LF"
CDS_LOCATION"R2209"
$SEC"1"
CDS_SEC"1";
"B"
$PN"2"50;
"A"
$PN"1"55;
%"Q_RES"
"1","(1475,8550)","0","pure_quanta","I64";
;
PART_NUMBER"CS00002JB13"
TOLERANCE"5%"
VALUE"0"
MATERIAL"CHIP"
$LOCATION"R2210"
CDS_LIB"pure_quanta"
WATTAGE"1/16W"
PACK_TYPE"0402LF"
CDS_LOCATION"R2210"
$SEC"1"
CDS_SEC"1";
"B"
$PN"2"51;
"A"
$PN"1"64;
%"Q_RES"
"1","(1475,8600)","0","pure_quanta","I65";
;
PART_NUMBER"CS00002JB13"
TOLERANCE"5%"
VALUE"0"
MATERIAL"CHIP"
$LOCATION"R2211"
PACK_TYPE"0402LF"
WATTAGE"1/16W"
CDS_LIB"pure_quanta"
CDS_LOCATION"R2211"
$SEC"1"
CDS_SEC"1";
"B"
$PN"2"46;
"A"
$PN"1"63;
%"UNIVERSAL_GND"
"1","(-975,9050)","0","logical_power","I67";
;
HDL_POWER"GND"
CDS_LIB"logical_power";
"A"21;
%"Q_CAP"
"1","(-975,9275)","2","pure_quanta","I68";
;
PART_NUMBER"CH4104K1B00"
VOLTAGE"25V"
TOLERANCE"10%"
MATERIAL"X7R"
VALUE"0.1UF"
PACK_TYPE"0402"
$LOCATION"C1613"
CDS_LIB"pure_quanta"
CDS_LOCATION"C1613"
$SEC"1"
CDS_SEC"1";
"B"
$PN"2"21;
"A"
$PN"1"7;
%"UNIVERSAL_GND"
"1","(-825,7675)","0","logical_power","I69";
;
CDS_LIB"logical_power"
HDL_POWER"GND";
"A"22;
%"UNIVERSAL_POWER"
"1","(1150,6550)","0","logical_power","I7";
;
HDL_POWER"P3V3_AUX"
CDS_LIB"logical_power";
"A"12;
%"UNIVERSAL_POWER"
"1","(-975,9600)","0","logical_power","I70";
;
HDL_POWER"P3V3_AUX"
CDS_LIB"logical_power";
"A"7;
%"Q_RES"
"2","(1150,6200)","0","pure_quanta","I8";
;
PART_NUMBER"CS15602FB03"
VALUE"560"
WATTAGE"1/16W"
MATERIAL"CHIP"
PACK_TYPE"0402LF"
TOLERANCE"1%"
$LOCATION"R977"
CDS_LIB"pure_quanta"
CDS_LOCATION"R977"
$SEC"1"
CDS_SEC"1";
"A"
$PN"1"12;
"B"
$PN"2"53;
%"Q_RES"
"2","(-4100,8100)","0","pure_quanta","I83";
;
PART_NUMBER"CS31002FB08"
MATERIAL"EMPTY"
VALUE"10K"
WATTAGE"1/16W"
TOLERANCE"1%"
PACK_TYPE"0402LF"
$LOCATION"R2310"
CDS_LIB"pure_quanta"
CDS_LOCATION"R2310"
$SEC"1"
CDS_SEC"1";
"A"
$PN"1"5;
"B"
$PN"2"32;
%"Q_RES"
"2","(-4350,8100)","0","pure_quanta","I84";
;
PART_NUMBER"CS31002FB08"
PACK_TYPE"0402LF"
MATERIAL"EMPTY"
WATTAGE"1/16W"
TOLERANCE"1%"
VALUE"10K"
$LOCATION"R2308"
CDS_LIB"pure_quanta"
CDS_LOCATION"R2308"
$SEC"1"
CDS_SEC"1";
"A"
$PN"1"5;
"B"
$PN"2"33;
%"Q_RES"
"2","(-4350,7450)","0","pure_quanta","I85";
;
PART_NUMBER"CS21002FB06"
WATTAGE"1/16W"
VALUE"1K"
MATERIAL"CHIP"
TOLERANCE"1%"
PACK_TYPE"0402LF"
$LOCATION"R2309"
CDS_LIB"pure_quanta"
CDS_LOCATION"R2309"
$SEC"1"
CDS_SEC"1";
"A"
$PN"1"33;
"B"
$PN"2"20;
%"Q_RES"
"2","(-4100,7450)","0","pure_quanta","I86";
;
PART_NUMBER"CS21002FB06"
MATERIAL"CHIP"
WATTAGE"1/16W"
VALUE"1K"
TOLERANCE"1%"
PACK_TYPE"0402LF"
$LOCATION"R2311"
CDS_LIB"pure_quanta"
CDS_LOCATION"R2311"
$SEC"1"
CDS_SEC"1";
"A"
$PN"1"32;
"B"
$PN"2"20;
%"UNIVERSAL_POWER"
"1","(-4350,8450)","0","logical_power","I87";
;
HDL_POWER"P3V3_AUX"
CDS_LIB"logical_power";
"A"5;
%"UNIVERSAL_GND"
"1","(-4350,7125)","0","logical_power","I88";
;
HDL_POWER"GND"
CDS_LIB"logical_power";
"A"20;
%"Q_RES"
"1","(-1925,8700)","0","pure_quanta","I97";
;
PART_NUMBER"CS00002JB13"
VALUE"0"
TOLERANCE"5%"
MATERIAL"CHIP"
$LOCATION"R2313"
WATTAGE"1/16W"
PACK_TYPE"0402LF"
CDS_LIB"pure_quanta"
CDS_LOCATION"R2313"
$SEC"1"
CDS_SEC"1";
"B"
$PN"2"31;
"A"
$PN"1"25;
END.
